(kicad_pcb
	(version 20260206)
	(generator "pcbnew")
	(generator_version "10.0")
	(general
		(thickness 1.21888)
		(legacy_teardrops no)
	)
	(paper "A4")
	(title_block
		(title "timecard-v9 — TimeCard-DC-V9_EXP.PcbDoc")
		(comment 1 "Time Appliance Project (Time Card) / footprints 49-54 of 402")
	)
	(layers
		(0 "F.Cu" signal "TOP")
		(4 "In1.Cu" signal "SGND")
		(6 "In2.Cu" signal "IN1")
		(8 "In3.Cu" signal "IN2")
		(10 "In4.Cu" signal "SGND1")
		(2 "B.Cu" signal "BOTTOM")
		(9 "F.Adhes" user "F.Adhesive")
		(11 "B.Adhes" user "B.Adhesive")
		(13 "F.Paste" user "Top Paste")
		(15 "B.Paste" user "Bottom Paste")
		(5 "F.SilkS" user "Top Overlay")
		(7 "B.SilkS" user "Bottom Overlay")
		(1 "F.Mask" user "Top Solder")
		(3 "B.Mask" user "Bottom Solder")
		(17 "Dwgs.User" user "User.Drawings")
		(19 "Cmts.User" user "User.Comments")
		(21 "Eco1.User" user "User.Eco1")
		(23 "Eco2.User" user "User.Eco2")
		(25 "Edge.Cuts" user)
		(27 "Margin" user)
		(31 "F.CrtYd" user "Top Courtyard")
		(29 "B.CrtYd" user "Bottom Courtyard")
		(35 "F.Fab" user "Top Component Center")
		(33 "B.Fab" user "Bottom Component Center")
	)
	(footprint "Vault:RESC1005X40X25LL05T10"
		(layer "F.Cu")
		(at 117.6216 78.5162 180)
		(property "Reference" "R176"
			(at 2.0968 0.073079 0)
			(unlocked yes)
			(layer "F.SilkS")
			(effects
				(font
					(size 0.762 0.762)
					(thickness 0.2032)
				)
			)
		)
		(property "Value" "49.9_1%_0402"
			(at -2.579871 8.798265 90)
			(unlocked yes)
			(layer "F.SilkS")
			(hide yes)
			(effects
				(font
					(size 0.762 0.762)
					(thickness 0.2032)
				)
			)
		)
		(sheetname "11-M2_RCB_MUX")
		(sheetfile "11-M2_RCB_MUX.kicad_sch")
		(duplicate_pad_numbers_are_jumpers no)
		(pad "1" smd rect
			(at -0.375 0 270)
			(size 0.45 0.5)
			(layers "F.Cu" "F.Mask" "F.Paste")
			(net "NetR176_1")
		)
		(pad "2" smd rect
			(at 0.375 0 270)
			(size 0.45 0.5)
			(layers "F.Cu" "F.Mask" "F.Paste")
			(net "GPS1_PIN11")
		)
	)
	(footprint "FPGA_CONN:SingleFPGAConn"
		(locked yes)
		(layer "F.Cu")
		(at 186.05909 109.97313 180)
		(property "Reference" "J34"
			(at 1.54102 -22.624419 180)
			(unlocked yes)
			(layer "F.SilkS")
			(effects
				(font
					(size 0.762 0.762)
					(thickness 0.2286)
				)
			)
		)
		(property "Value" "Single FPGA Conn"
			(at 9.25453 3.621231 180)
			(unlocked yes)
			(layer "F.SilkS")
			(hide yes)
			(effects
				(font
					(size 0.762 0.762)
					(thickness 0.2286)
				)
			)
		)
		(sheetname "07-FPGA")
		(sheetfile "07-FPGA.kicad_sch")
		(duplicate_pad_numbers_are_jumpers no)
		(fp_line
			(start 2 0.70002)
			(end 1.40005 1.24993)
			(stroke
				(width 0.15011)
				(type solid)
			)
			(layer "F.SilkS")
		)
		(fp_line
			(start 2 0.03302)
			(end 2 0.70002)
			(stroke
				(width 0.15011)
				(type solid)
			)
			(layer "F.SilkS")
		)
		(fp_line
			(start 2 -20.69999)
			(end 2 -20.03298)
			(stroke
				(width 0.15011)
				(type solid)
			)
			(layer "F.SilkS")
		)
		(fp_line
			(start 2 -20.69999)
			(end 1.40005 -21.2499)
			(stroke
				(width 0.15011)
				(type solid)
			)
			(layer "F.SilkS")
		)
		(fp_line
			(start 1.40005 1.24993)
			(end -1.40004 1.24993)
			(stroke
				(width 0.15011)
				(type solid)
			)
			(layer "F.SilkS")
		)
		(fp_line
			(start 1.40005 -21.2499)
			(end -1.40004 -21.2499)
			(stroke
				(width 0.15011)
				(type solid)
			)
			(layer "F.SilkS")
		)
		(fp_line
			(start -1.40004 0.70002)
			(end -1.40004 1.24993)
			(stroke
				(width 0.15011)
				(type solid)
			)
			(layer "F.SilkS")
		)
		(fp_line
			(start -1.40004 0.70002)
			(end -1.99999 0.70002)
			(stroke
				(width 0.15011)
				(type solid)
			)
			(layer "F.SilkS")
		)
		(fp_line
			(start -1.40004 -20.69999)
			(end -1.99999 -20.69999)
			(stroke
				(width 0.15011)
				(type solid)
			)
			(layer "F.SilkS")
		)
		(fp_line
			(start -1.40004 -21.2499)
			(end -1.40004 -20.69999)
			(stroke
				(width 0.15011)
				(type solid)
			)
			(layer "F.SilkS")
		)
		(fp_line
			(start -1.99999 0.03302)
			(end -1.99999 0.70002)
			(stroke
				(width 0.15011)
				(type solid)
			)
			(layer "F.SilkS")
		)
		(fp_line
			(start -1.99999 -20.69999)
			(end -1.99999 -20.03298)
			(stroke
				(width 0.15011)
				(type solid)
			)
			(layer "F.SilkS")
		)
		(fp_circle
			(center 3.5052 -0.22454)
			(end 3.5052 -0.02439)
			(stroke
				(width 0.40005)
				(type solid)
			)
			(fill no)
			(layer "F.SilkS")
		)
		(pad "1" smd rect
			(at 2.02489 -0.24994 180)
			(size 1.54991 0.24994)
			(layers "F.Cu" "F.Mask" "F.Paste")
			(net "+5.0V")
		)
		(pad "2" smd rect
			(at -2.02488 -0.24994 180)
			(size 1.54991 0.24994)
			(layers "F.Cu" "F.Mask" "F.Paste")
			(net "+5.0V")
		)
		(pad "3" smd rect
			(at 2.02489 -0.75007 180)
			(size 1.54991 0.24994)
			(layers "F.Cu" "F.Mask" "F.Paste")
			(net "+5.0V")
		)
		(pad "4" smd rect
			(at -2.02488 -0.75007 180)
			(size 1.54991 0.24994)
			(layers "F.Cu" "F.Mask" "F.Paste")
			(net "+5.0V")
		)
		(pad "5" smd rect
			(at 2.02489 -1.24994 180)
			(size 1.54991 0.24994)
			(layers "F.Cu" "F.Mask" "F.Paste")
			(net "+5.0V")
		)
		(pad "6" smd rect
			(at -2.02488 -1.24994 180)
			(size 1.54991 0.24994)
			(layers "F.Cu" "F.Mask" "F.Paste")
			(net "+5.0V")
		)
		(pad "7" smd rect
			(at 2.02489 -1.75006 180)
			(size 1.54991 0.24994)
			(layers "F.Cu" "F.Mask" "F.Paste")
			(net "+5.0V")
		)
		(pad "8" smd rect
			(at -2.02488 -1.75006 180)
			(size 1.54991 0.24994)
			(layers "F.Cu" "F.Mask" "F.Paste")
			(net "+5.0V")
		)
		(pad "9" smd rect
			(at 2.02489 -2.24994 180)
			(size 1.54991 0.24994)
			(layers "F.Cu" "F.Mask" "F.Paste")
			(net "GND")
		)
		(pad "10" smd rect
			(at -2.02488 -2.24994 180)
			(size 1.54991 0.24994)
			(layers "F.Cu" "F.Mask" "F.Paste")
			(net "GND")
		)
		(pad "11" smd rect
			(at 2.02489 -2.75006 180)
			(size 1.54991 0.24994)
			(layers "F.Cu" "F.Mask" "F.Paste")
		)
		(pad "12" smd rect
			(at -2.02488 -2.75006 180)
			(size 1.54991 0.24994)
			(layers "F.Cu" "F.Mask" "F.Paste")
		)
		(pad "13" smd rect
			(at 2.02489 -3.24993 180)
			(size 1.54991 0.24994)
			(layers "F.Cu" "F.Mask" "F.Paste")
		)
		(pad "14" smd rect
			(at -2.02488 -3.24993 180)
			(size 1.54991 0.24994)
			(layers "F.Cu" "F.Mask" "F.Paste")
		)
		(pad "15" smd rect
			(at 2.02489 -3.75006 180)
			(size 1.54991 0.24994)
			(layers "F.Cu" "F.Mask" "F.Paste")
		)
		(pad "16" smd rect
			(at -2.02488 -3.75006 180)
			(size 1.54991 0.24994)
			(layers "F.Cu" "F.Mask" "F.Paste")
		)
		(pad "17" smd rect
			(at 2.02489 -4.24993 180)
			(size 1.54991 0.24994)
			(layers "F.Cu" "F.Mask" "F.Paste")
		)
		(pad "18" smd rect
			(at -2.02488 -4.24993 180)
			(size 1.54991 0.24994)
			(layers "F.Cu" "F.Mask" "F.Paste")
		)
		(pad "19" smd rect
			(at 2.02489 -4.75006 180)
			(size 1.54991 0.24994)
			(layers "F.Cu" "F.Mask" "F.Paste")
			(net "GND")
		)
		(pad "20" smd rect
			(at -2.02488 -4.75006 180)
			(size 1.54991 0.24994)
			(layers "F.Cu" "F.Mask" "F.Paste")
			(net "GND")
		)
		(pad "21" smd rect
			(at 2.02489 -5.24993 180)
			(size 1.54991 0.24994)
			(layers "F.Cu" "F.Mask" "F.Paste")
		)
		(pad "22" smd rect
			(at -2.02488 -5.24993 180)
			(size 1.54991 0.24994)
			(layers "F.Cu" "F.Mask" "F.Paste")
			(net "GPS1_RST")
		)
		(pad "23" smd rect
			(at 2.02489 -5.75006 180)
			(size 1.54991 0.24994)
			(layers "F.Cu" "F.Mask" "F.Paste")
		)
		(pad "24" smd rect
			(at -2.02488 -5.75006 180)
			(size 1.54991 0.24994)
			(layers "F.Cu" "F.Mask" "F.Paste")
		)
		(pad "25" smd rect
			(at 2.02489 -6.24993 180)
			(size 1.54991 0.24994)
			(layers "F.Cu" "F.Mask" "F.Paste")
		)
		(pad "26" smd rect
			(at -2.02488 -6.24993 180)
			(size 1.54991 0.24994)
			(layers "F.Cu" "F.Mask" "F.Paste")
		)
		(pad "27" smd rect
			(at 2.02489 -6.75005 180)
			(size 1.54991 0.24994)
			(layers "F.Cu" "F.Mask" "F.Paste")
		)
		(pad "28" smd rect
			(at -2.02488 -6.75005 180)
			(size 1.54991 0.24994)
			(layers "F.Cu" "F.Mask" "F.Paste")
		)
		(pad "29" smd rect
			(at 2.02489 -7.24993 180)
			(size 1.54991 0.24994)
			(layers "F.Cu" "F.Mask" "F.Paste")
			(net "GND")
		)
		(pad "30" smd rect
			(at -2.02488 -7.24993 180)
			(size 1.54991 0.24994)
			(layers "F.Cu" "F.Mask" "F.Paste")
			(net "GND")
		)
		(pad "31" smd rect
			(at 2.02489 -7.75005 180)
			(size 1.54991 0.24994)
			(layers "F.Cu" "F.Mask" "F.Paste")
		)
		(pad "32" smd rect
			(at -2.02488 -7.75005 180)
			(size 1.54991 0.24994)
			(layers "F.Cu" "F.Mask" "F.Paste")
			(net "GPS1_TP1")
		)
		(pad "33" smd rect
			(at 2.02489 -8.24992 180)
			(size 1.54991 0.24994)
			(layers "F.Cu" "F.Mask" "F.Paste")
		)
		(pad "34" smd rect
			(at -2.02488 -8.24992 180)
			(size 1.54991 0.24994)
			(layers "F.Cu" "F.Mask" "F.Paste")
			(net "GPS1_TP2")
		)
		(pad "35" smd rect
			(at 2.02489 -8.75005 180)
			(size 1.54991 0.24994)
			(layers "F.Cu" "F.Mask" "F.Paste")
		)
		(pad "36" smd rect
			(at -2.02488 -8.75005 180)
			(size 1.54991 0.24994)
			(layers "F.Cu" "F.Mask" "F.Paste")
		)
		(pad "37" smd rect
			(at 2.02489 -9.24992 180)
			(size 1.54991 0.24994)
			(layers "F.Cu" "F.Mask" "F.Paste")
		)
		(pad "38" smd rect
			(at -2.02488 -9.24992 180)
			(size 1.54991 0.24994)
			(layers "F.Cu" "F.Mask" "F.Paste")
		)
		(pad "39" smd rect
			(at 2.02489 -9.75005 180)
			(size 1.54991 0.24994)
			(layers "F.Cu" "F.Mask" "F.Paste")
			(net "GND")
		)
		(pad "40" smd rect
			(at -2.02488 -9.75005 180)
			(size 1.54991 0.24994)
			(layers "F.Cu" "F.Mask" "F.Paste")
			(net "GND")
		)
		(pad "41" smd rect
			(at 2.02489 -10.24992 180)
			(size 1.54991 0.24994)
			(layers "F.Cu" "F.Mask" "F.Paste")
		)
		(pad "42" smd rect
			(at -2.02488 -10.24992 180)
			(size 1.54991 0.24994)
			(layers "F.Cu" "F.Mask" "F.Paste")
		)
		(pad "43" smd rect
			(at 2.02489 -10.75005 180)
			(size 1.54991 0.24994)
			(layers "F.Cu" "F.Mask" "F.Paste")
		)
		(pad "44" smd rect
			(at -2.02488 -10.75005 180)
			(size 1.54991 0.24994)
			(layers "F.Cu" "F.Mask" "F.Paste")
			(net "EXT_EEPROM_WP")
		)
		(pad "45" smd rect
			(at 2.02489 -11.24992 180)
			(size 1.54991 0.24994)
			(layers "F.Cu" "F.Mask" "F.Paste")
		)
		(pad "46" smd rect
			(at -2.02488 -11.24992 180)
			(size 1.54991 0.24994)
			(layers "F.Cu" "F.Mask" "F.Paste")
		)
		(pad "47" smd rect
			(at 2.02489 -11.75004 180)
			(size 1.54991 0.24994)
			(layers "F.Cu" "F.Mask" "F.Paste")
		)
		(pad "48" smd rect
			(at -2.02488 -11.75004 180)
			(size 1.54991 0.24994)
			(layers "F.Cu" "F.Mask" "F.Paste")
		)
		(pad "49" smd rect
			(at 2.02489 -12.24992 180)
			(size 1.54991 0.24994)
			(layers "F.Cu" "F.Mask" "F.Paste")
			(net "GND")
		)
		(pad "50" smd rect
			(at -2.02488 -12.24992 180)
			(size 1.54991 0.24994)
			(layers "F.Cu" "F.Mask" "F.Paste")
			(net "GND")
		)
		(pad "51" smd rect
			(at 2.02489 -12.75004 180)
			(size 1.54991 0.24994)
			(layers "F.Cu" "F.Mask" "F.Paste")
		)
		(pad "52" smd rect
			(at -2.02488 -12.75004 180)
			(size 1.54991 0.24994)
			(layers "F.Cu" "F.Mask" "F.Paste")
		)
		(pad "53" smd rect
			(at 2.02489 -13.24991 180)
			(size 1.54991 0.24994)
			(layers "F.Cu" "F.Mask" "F.Paste")
		)
		(pad "54" smd rect
			(at -2.02488 -13.24991 180)
			(size 1.54991 0.24994)
			(layers "F.Cu" "F.Mask" "F.Paste")
		)
		(pad "55" smd rect
			(at 2.02489 -13.75004 180)
			(size 1.54991 0.24994)
			(layers "F.Cu" "F.Mask" "F.Paste")
		)
		(pad "56" smd rect
			(at -2.02488 -13.75004 180)
			(size 1.54991 0.24994)
			(layers "F.Cu" "F.Mask" "F.Paste")
		)
		(pad "57" smd rect
			(at 2.02489 -14.24991 180)
			(size 1.54991 0.24994)
			(layers "F.Cu" "F.Mask" "F.Paste")
		)
		(pad "58" smd rect
			(at -2.02488 -14.24991 180)
			(size 1.54991 0.24994)
			(layers "F.Cu" "F.Mask" "F.Paste")
		)
		(pad "59" smd rect
			(at 2.02489 -14.75004 180)
			(size 1.54991 0.24994)
			(layers "F.Cu" "F.Mask" "F.Paste")
			(net "GND")
		)
		(pad "60" smd rect
			(at -2.02488 -14.75004 180)
			(size 1.54991 0.24994)
			(layers "F.Cu" "F.Mask" "F.Paste")
			(net "GND")
		)
		(pad "61" smd rect
			(at 2.02489 -15.24991 180)
			(size 1.54991 0.24994)
			(layers "F.Cu" "F.Mask" "F.Paste")
		)
		(pad "62" smd rect
			(at -2.02488 -15.24991 180)
			(size 1.54991 0.24994)
			(layers "F.Cu" "F.Mask" "F.Paste")
		)
		(pad "63" smd rect
			(at 2.02489 -15.75004 180)
			(size 1.54991 0.24994)
			(layers "F.Cu" "F.Mask" "F.Paste")
		)
		(pad "64" smd rect
			(at -2.02488 -15.75004 180)
			(size 1.54991 0.24994)
			(layers "F.Cu" "F.Mask" "F.Paste")
		)
		(pad "65" smd rect
			(at 2.02489 -16.24991 180)
			(size 1.54991 0.24994)
			(layers "F.Cu" "F.Mask" "F.Paste")
		)
		(pad "66" smd rect
			(at -2.02488 -16.24991 180)
			(size 1.54991 0.24994)
			(layers "F.Cu" "F.Mask" "F.Paste")
		)
		(pad "67" smd rect
			(at 2.02489 -16.75003 180)
			(size 1.54991 0.24994)
			(layers "F.Cu" "F.Mask" "F.Paste")
			(net "KEY2")
		)
		(pad "68" smd rect
			(at -2.02488 -16.75003 180)
			(size 1.54991 0.24994)
			(layers "F.Cu" "F.Mask" "F.Paste")
		)
		(pad "69" smd rect
			(at 2.02489 -17.24991 180)
			(size 1.54991 0.24994)
			(layers "F.Cu" "F.Mask" "F.Paste")
			(net "GND")
		)
		(pad "70" smd rect
			(at -2.02488 -17.24991 180)
			(size 1.54991 0.24994)
			(layers "F.Cu" "F.Mask" "F.Paste")
			(net "GND")
		)
		(pad "71" smd rect
			(at 2.02489 -17.75003 180)
			(size 1.54991 0.24994)
			(layers "F.Cu" "F.Mask" "F.Paste")
			(net "LED4")
		)
		(pad "72" smd rect
			(at -2.02488 -17.75003 180)
			(size 1.54991 0.24994)
			(layers "F.Cu" "F.Mask" "F.Paste")
		)
		(pad "73" smd rect
			(at 2.02489 -18.2499 180)
			(size 1.54991 0.24994)
			(layers "F.Cu" "F.Mask" "F.Paste")
			(net "LED3")
		)
		(pad "74" smd rect
			(at -2.02488 -18.2499 180)
			(size 1.54991 0.24994)
			(layers "F.Cu" "F.Mask" "F.Paste")
		)
		(pad "75" smd rect
			(at 2.02489 -18.75003 180)
			(size 1.54991 0.24994)
			(layers "F.Cu" "F.Mask" "F.Paste")
			(net "LED2")
		)
		(pad "76" smd rect
			(at -2.02488 -18.75003 180)
			(size 1.54991 0.24994)
			(layers "F.Cu" "F.Mask" "F.Paste")
		)
		(pad "77" smd rect
			(at 2.02489 -19.2499 180)
			(size 1.54991 0.24994)
			(layers "F.Cu" "F.Mask" "F.Paste")
			(net "LED1")
		)
		(pad "78" smd rect
			(at -2.02488 -19.2499 180)
			(size 1.54991 0.24994)
			(layers "F.Cu" "F.Mask" "F.Paste")
		)
		(pad "79" smd rect
			(at 2.02489 -19.75003 180)
			(size 1.54991 0.24994)
			(layers "F.Cu" "F.Mask" "F.Paste")
		)
		(pad "80" smd rect
			(at -2.02488 -19.75003 180)
			(size 1.54991 0.24994)
			(layers "F.Cu" "F.Mask" "F.Paste")
		)
		(pad "81" smd rect
			(at 0.01136 1.17626 180)
			(size 1.70002 1.35001)
			(layers "F.Cu" "F.Mask" "F.Paste")
		)
		(pad "82" thru_hole circle
			(at 0 0 180)
			(size 0.55016 0.55016)
			(drill 0.55016)
			(layers "*.Cu" "*.Mask")
			(remove_unused_layers no)
			(thermal_bridge_angle 90)
		)
		(pad "83" thru_hole circle
			(at 0 -19.99996 180)
			(size 0.55016 0.55016)
			(drill 0.55016)
			(layers "*.Cu" "*.Mask")
			(remove_unused_layers no)
			(thermal_bridge_angle 90)
		)
		(pad "84" smd rect
			(at 0.01136 -21.17375 180)
			(size 1.70002 1.35001)
			(layers "F.Cu" "F.Mask" "F.Paste")
		)
	)
	(footprint "Vault:RESC1005X40X25NL10T10"
		(layer "F.Cu")
		(at 78.5216 115.9162)
		(property "Reference" "R29"
			(at -2.5 1.593345 0)
			(unlocked yes)
			(layer "F.SilkS")
			(effects
				(font
					(size 0.762 0.762)
					(thickness 0.2286)
				)
				(justify left bottom)
			)
		)
		(property "Value" "4.7K_1%_0402"
			(at -0.4445 3.636645 0)
			(unlocked yes)
			(layer "F.SilkS")
			(hide yes)
			(effects
				(font
					(size 0.762 0.762)
					(thickness 0.2286)
				)
				(justify left bottom)
			)
		)
		(sheetname "01-USER_IO")
		(sheetfile "01-USER_IO.kicad_sch")
		(duplicate_pad_numbers_are_jumpers no)
		(pad "1" smd rect
			(at -0.425 0 90)
			(size 0.6 0.65)
			(layers "F.Cu" "F.Mask" "F.Paste")
			(net "+3.3V")
		)
		(pad "2" smd rect
			(at 0.425 0 90)
			(size 0.6 0.65)
			(layers "F.Cu" "F.Mask" "F.Paste")
			(net "ANT2_IO_OUT")
		)
	)
	(footprint "Resistors:RESC2012X50N"
		(layer "F.Cu")
		(at 216.8416 145.71545)
		(property "Reference" "R20"
			(at -1.2 -1.506645 0)
			(unlocked yes)
			(layer "F.SilkS")
			(effects
				(font
					(size 0.762 0.762)
					(thickness 0.2286)
				)
				(justify left bottom)
			)
		)
		(property "Value" "CRCW080533R0FKEA"
			(at 4.25585 -6.908405 0)
			(unlocked yes)
			(layer "F.SilkS")
			(hide yes)
			(effects
				(font
					(size 0.762 0.762)
					(thickness 0.2286)
				)
				(justify left bottom)
			)
		)
		(sheetname "04-PCIe_JTAG")
		(sheetfile "04-PCIe_JTAG.kicad_sch")
		(duplicate_pad_numbers_are_jumpers no)
		(fp_line
			(start 0 0.762)
			(end 0 -0.762)
			(stroke
				(width 0.1524)
				(type solid)
			)
			(layer "F.SilkS")
		)
		(pad "1" smd rect
			(at -1 0 90)
			(size 1.45 0.95)
			(layers "F.Cu" "F.Mask" "F.Paste")
			(net "FPGA_TMS")
		)
		(pad "2" smd rect
			(at 1 0 90)
			(size 1.45 0.95)
			(layers "F.Cu" "F.Mask" "F.Paste")
			(net "NetP4_5")
		)
	)
	(footprint "Vault:RESC1005X40X25NL05T05"
		(layer "F.Cu")
		(at 150.6216 130.4162)
		(property "Reference" "R93"
			(at -2.1714 0.226921 0)
			(unlocked yes)
			(layer "F.SilkS")
			(effects
				(font
					(size 0.762 0.762)
					(thickness 0.2286)
				)
			)
		)
		(property "Value" "27_1%_0402"
			(at -2.732271 7.37632 270)
			(unlocked yes)
			(layer "F.SilkS")
			(hide yes)
			(effects
				(font
					(size 0.762 0.762)
					(thickness 0.2286)
				)
			)
		)
		(sheetname "09-USBUart_PPSMUX_UARTMUX")
		(sheetfile "09-USBUart_PPSMUX_UARTMUX.kicad_sch")
		(duplicate_pad_numbers_are_jumpers no)
		(pad "1" smd rect
			(at -0.45 0 90)
			(size 0.55 0.55)
			(layers "F.Cu" "F.Mask" "F.Paste")
			(net "GPS2_RX_FPGA")
		)
		(pad "2" smd rect
			(at 0.45 0 90)
			(size 0.55 0.55)
			(layers "F.Cu" "F.Mask" "F.Paste")
			(net "NetR93_2")
		)
	)
	(footprint "Vault:RESC1005X40X25NL05T05"
		(layer "F.Cu")
		(at 166.7216 115.2162)
		(property "Reference" "R128"
			(at -2.5968 0.126921 0)
			(unlocked yes)
			(layer "F.SilkS")
			(effects
				(font
					(size 0.762 0.762)
					(thickness 0.2032)
				)
			)
		)
		(property "Value" "27_1%_0402"
			(at -2.732271 7.35092 270)
			(unlocked yes)
			(layer "F.SilkS")
			(hide yes)
			(effects
				(font
					(size 0.762 0.762)
					(thickness 0.2032)
				)
			)
		)
		(sheetname "08-DIPSwitches_I2C")
		(sheetfile "08-DIPSwitches_I2C.kicad_sch")
		(duplicate_pad_numbers_are_jumpers no)
		(pad "1" smd rect
			(at -0.45 0 90)
			(size 0.55 0.55)
			(layers "F.Cu" "F.Mask" "F.Paste")
			(net "GND")
		)
		(pad "2" smd rect
			(at 0.45 0 90)
			(size 0.55 0.55)
			(layers "F.Cu" "F.Mask" "F.Paste")
			(net "NetR128_2")
		)
	)
)
